(kicad_pcb
	(version 20260206)
	(generator "pcbnew")
	(generator_version "10.0")
	(general
		(thickness 1.6)
		(legacy_teardrops no)
	)
	(paper "A4")
	(title_block
		(title "Bryce Canyon_R.DPB_16317-1_OCP.brd")
		(comment 1 "Bryce Canyon / footprints 1149-1151 of 2099")
	)
	(layers
		(0 "F.Cu" signal "TOP")
		(4 "In1.Cu" signal "L2GND")
		(6 "In2.Cu" signal "L3")
		(8 "In3.Cu" signal "L4VCC")
		(10 "In4.Cu" signal "L5VCC")
		(12 "In5.Cu" signal "L6")
		(14 "In6.Cu" signal "L7GND")
		(2 "B.Cu" signal "BOTTOM")
		(9 "F.Adhes" user "F.Adhesive")
		(11 "B.Adhes" user "B.Adhesive")
		(13 "F.Paste" user "Package Geometry/Pastemask Top")
		(15 "B.Paste" user "Package Geometry/Pastemask Bottom")
		(5 "F.SilkS" user "Ref Des/Silkscreen Top")
		(7 "B.SilkS" user "Ref Des/Silkscreen Bottom")
		(1 "F.Mask" user "Board Geometry/Soldermask Top")
		(3 "B.Mask" user "Board Geometry/Soldermask Bottom")
		(17 "Dwgs.User" user "User.Drawings")
		(19 "Cmts.User" user "User.Comments")
		(21 "Eco1.User" user "User.Eco1")
		(23 "Eco2.User" user "User.Eco2")
		(25 "Edge.Cuts" user "Board Geometry/Outline")
		(27 "Margin" user)
		(31 "F.CrtYd" user "Package Geometry/Place Bound Top")
		(29 "B.CrtYd" user "Package Geometry/Place Bound Bottom")
		(35 "F.Fab" user "Ref Des/Assembly Top")
		(33 "B.Fab" user "Ref Des/Assembly Bottom")
	)
	(footprint ""
		(layer "F.Cu")
		(at 78.11135 -217.413586 -90)
		(property "Reference" "R171"
			(at 0 0 270)
			(layer "F.SilkS")
			(hide yes)
			(effects
				(font
					(size 1.27 1.27)
				)
			)
		)
		(property "Value" "4K7R2F-GP"
			(at 0.064008 -3.993896 270)
			(unlocked yes)
			(layer "F.Fab")
			(hide yes)
			(effects
				(font
					(size 1.016 1.016)
					(thickness 0.1524)
				)
			)
		)
		(property "Device Type" "R402H16"
			(at 0.064008 -5.517896 270)
			(unlocked yes)
			(layer "F.Fab")
			(hide yes)
			(effects
				(font
					(size 1.016 1.016)
					(thickness 0.1524)
				)
			)
		)
		(duplicate_pad_numbers_are_jumpers no)
		(fp_line
			(start -0.508 -0.9398)
			(end -0.508 0.9398)
			(stroke
				(width 0.1524)
				(type default)
			)
			(layer "F.SilkS")
		)
		(fp_line
			(start 0.508 -0.9398)
			(end -0.508 -0.9398)
			(stroke
				(width 0.1524)
				(type default)
			)
			(layer "F.SilkS")
		)
		(fp_rect
			(start -0.508 0.9398)
			(end 0.508 -0.9398)
			(stroke
				(width 0)
				(type default)
			)
			(fill no)
			(layer "F.CrtYd")
		)
		(fp_rect
			(start -0.508 0.9398)
			(end 0.508 -0.9398)
			(stroke
				(width 0)
				(type default)
			)
			(fill no)
			(layer "F.Fab")
		)
		(pad "1" smd custom
			(at 0 -0.4445 270)
			(size 0.1397 0.1397)
			(layers "F.Cu" "F.Mask" "F.Paste")
			(net "DRIVE_B_2_FLT_LED")
			(options
				(clearance outline)
				(anchor circle)
			)
			(primitives
				(gr_poly
					(pts
						(arc
							(start -0.1778 -0.2794)
							(mid -0.249642 -0.249642)
							(end -0.2794 -0.1778)
						)
						(arc
							(start -0.2794 0.1778)
							(mid -0.249642 0.249642)
							(end -0.1778 0.2794)
						)
						(arc
							(start 0.1778 0.2794)
							(mid 0.249642 0.249642)
							(end 0.2794 0.1778)
						)
						(arc
							(start 0.2794 -0.1778)
							(mid 0.249642 -0.249642)
							(end 0.1778 -0.2794)
						)
					)
					(width 0)
					(fill yes)
				)
			)
		)
		(pad "2" smd custom
			(at 0 0.4445 270)
			(size 0.1397 0.1397)
			(layers "F.Cu" "F.Mask" "F.Paste")
			(net "GND")
			(options
				(clearance outline)
				(anchor circle)
			)
			(primitives
				(gr_poly
					(pts
						(arc
							(start -0.1778 -0.2794)
							(mid -0.249642 -0.249642)
							(end -0.2794 -0.1778)
						)
						(arc
							(start -0.2794 0.1778)
							(mid -0.249642 0.249642)
							(end -0.1778 0.2794)
						)
						(arc
							(start 0.1778 0.2794)
							(mid 0.249642 0.249642)
							(end 0.2794 0.1778)
						)
						(arc
							(start 0.2794 -0.1778)
							(mid 0.249642 -0.249642)
							(end 0.1778 -0.2794)
						)
					)
					(width 0)
					(fill yes)
				)
			)
		)
	)
	(footprint ""
		(layer "F.Cu")
		(at 73.861168 -99.874578 90)
		(property "Reference" "Q257"
			(at 0 0 90)
			(layer "F.SilkS")
			(hide yes)
			(effects
				(font
					(size 1.27 1.27)
				)
			)
		)
		(property "Value" "SSM3K324R-GP"
			(at 0.127 -8.9662 90)
			(unlocked yes)
			(layer "F.Fab")
			(hide yes)
			(effects
				(font
					(size 1.016 1.016)
					(thickness 0.1524)
				)
			)
		)
		(property "Device Type" "SOT23DGS2D4H35"
			(at 0.127 -10.4902 90)
			(unlocked yes)
			(layer "F.Fab")
			(hide yes)
			(effects
				(font
					(size 1.016 1.016)
					(thickness 0.1524)
				)
			)
		)
		(duplicate_pad_numbers_are_jumpers no)
		(fp_line
			(start 1.651 -1.778)
			(end -1.651 -1.778)
			(stroke
				(width 0.1524)
				(type default)
			)
			(layer "F.SilkS")
		)
		(fp_line
			(start -1.651 -1.778)
			(end -1.651 1.778)
			(stroke
				(width 0.1524)
				(type default)
			)
			(layer "F.SilkS")
		)
		(fp_line
			(start 1.651 1.778)
			(end 1.651 -1.778)
			(stroke
				(width 0.1524)
				(type default)
			)
			(layer "F.SilkS")
		)
		(fp_line
			(start -1.651 1.778)
			(end 1.651 1.778)
			(stroke
				(width 0.1524)
				(type default)
			)
			(layer "F.SilkS")
		)
		(fp_poly
			(pts
				(xy -1.778 1.8796) (xy -1.778 -1.8796) (xy 1.778 -1.8796) (xy 1.778 1.8796)
			)
			(stroke
				(width 0)
				(type default)
			)
			(fill no)
			(layer "F.CrtYd")
		)
		(fp_poly
			(pts
				(xy -1.778 1.8796) (xy -1.778 -1.8796) (xy 1.778 -1.8796) (xy 1.778 1.8796)
			)
			(stroke
				(width 0)
				(type default)
			)
			(fill no)
			(layer "F.Fab")
		)
		(pad "D" smd custom
			(at 0 -0.9525 90)
			(size 0.1905 0.1905)
			(layers "F.Cu" "F.Mask" "F.Paste")
			(net "DRV_ACT_14_N")
			(options
				(clearance outline)
				(anchor circle)
			)
			(primitives
				(gr_poly
					(pts
						(arc
							(start -0.1778 0.5715)
							(mid -0.321484 0.511984)
							(end -0.381 0.3683)
						)
						(arc
							(start -0.381 -0.3683)
							(mid -0.321484 -0.511984)
							(end -0.1778 -0.5715)
						)
						(arc
							(start 0.1778 -0.5715)
							(mid 0.321484 -0.511984)
							(end 0.381 -0.3683)
						)
						(arc
							(start 0.381 0.3683)
							(mid 0.321484 0.511984)
							(end 0.1778 0.5715)
						)
					)
					(width 0)
					(fill yes)
				)
			)
		)
		(pad "G" smd custom
			(at -0.98425 0.9525 90)
			(size 0.1905 0.1905)
			(layers "F.Cu" "F.Mask" "F.Paste")
			(net "DRIVE_B_14_ACT")
			(options
				(clearance outline)
				(anchor circle)
			)
			(primitives
				(gr_poly
					(pts
						(arc
							(start -0.1778 0.5715)
							(mid -0.321484 0.511984)
							(end -0.381 0.3683)
						)
						(arc
							(start -0.381 -0.3683)
							(mid -0.321484 -0.511984)
							(end -0.1778 -0.5715)
						)
						(arc
							(start 0.1778 -0.5715)
							(mid 0.321484 -0.511984)
							(end 0.381 -0.3683)
						)
						(arc
							(start 0.381 0.3683)
							(mid 0.321484 0.511984)
							(end 0.1778 0.5715)
						)
					)
					(width 0)
					(fill yes)
				)
			)
		)
		(pad "S" smd custom
			(at 0.98425 0.9525 90)
			(size 0.1905 0.1905)
			(layers "F.Cu" "F.Mask" "F.Paste")
			(net "GND")
			(options
				(clearance outline)
				(anchor circle)
			)
			(primitives
				(gr_poly
					(pts
						(arc
							(start -0.1778 0.5715)
							(mid -0.321484 0.511984)
							(end -0.381 0.3683)
						)
						(arc
							(start -0.381 -0.3683)
							(mid -0.321484 -0.511984)
							(end -0.1778 -0.5715)
						)
						(arc
							(start 0.1778 -0.5715)
							(mid 0.321484 -0.511984)
							(end 0.381 -0.3683)
						)
						(arc
							(start 0.381 0.3683)
							(mid 0.321484 0.511984)
							(end 0.1778 0.5715)
						)
					)
					(width 0)
					(fill yes)
				)
			)
		)
	)
	(footprint ""
		(layer "F.Cu")
		(at 185.950098 -28.910026 -90)
		(property "Reference" "HDDSAS29"
			(at 0 0 270)
			(layer "F.SilkS")
			(hide yes)
			(effects
				(font
					(size 1.27 1.27)
				)
			)
		)
		(property "Value" "SKT-SAS15P-14P-45-GP"
			(at -20.7645 -8.9789 270)
			(unlocked yes)
			(layer "F.Fab")
			(hide yes)
			(effects
				(font
					(size 1.016 1.016)
					(thickness 0.1524)
				)
			)
		)
		(property "Device Type" "10120818-001C-TRLF"
			(at -20.7645 -10.5029 270)
			(unlocked yes)
			(layer "F.Fab")
			(hide yes)
			(effects
				(font
					(size 1.016 1.016)
					(thickness 0.1524)
				)
			)
		)
		(duplicate_pad_numbers_are_jumpers no)
		(fp_line
			(start 1.651 4.2926)
			(end 1.651 3.0099)
			(stroke
				(width 0.1524)
				(type default)
			)
			(layer "F.SilkS")
		)
		(fp_line
			(start 8.509 4.2926)
			(end 1.651 4.2926)
			(stroke
				(width 0.1524)
				(type default)
			)
			(layer "F.SilkS")
		)
		(fp_line
			(start -23.4188 3.0099)
			(end -23.4188 -3.2512)
			(stroke
				(width 0.1524)
				(type default)
			)
			(layer "F.SilkS")
		)
		(fp_line
			(start 1.651 3.0099)
			(end -23.4188 3.0099)
			(stroke
				(width 0.1524)
				(type default)
			)
			(layer "F.SilkS")
		)
		(fp_line
			(start 8.509 3.0099)
			(end 8.509 4.2926)
			(stroke
				(width 0.1524)
				(type default)
			)
			(layer "F.SilkS")
		)
		(fp_line
			(start 23.4188 3.0099)
			(end 8.509 3.0099)
			(stroke
				(width 0.1524)
				(type default)
			)
			(layer "F.SilkS")
		)
		(fp_line
			(start -23.4188 -3.2512)
			(end 23.4188 -3.2512)
			(stroke
				(width 0.1524)
				(type default)
			)
			(layer "F.SilkS")
		)
		(fp_line
			(start 23.4188 -3.2512)
			(end 23.4188 3.0099)
			(stroke
				(width 0.1524)
				(type default)
			)
			(layer "F.SilkS")
		)
		(fp_line
			(start 15.5067 -3.3401)
			(end 16.2687 -3.3401)
			(stroke
				(width 0.3302)
				(type default)
			)
			(layer "F.SilkS")
		)
		(fp_poly
			(pts
				(xy 15.868904 -3.230372) (xy 16.503904 -3.865372) (xy 15.233904 -3.865372)
			)
			(stroke
				(width 0)
				(type default)
			)
			(fill yes)
			(layer "F.SilkS")
		)
		(fp_poly
			(pts
				(xy -22.8727 -2.7559) (xy 22.8727 -2.7559) (xy 22.8727 2.7559) (xy 8.255 2.7559) (xy 8.255 3.5179)
				(xy 1.905 3.5179) (xy 1.905 2.7559) (xy -22.8727 2.7559)
			)
			(stroke
				(width 0)
				(type default)
			)
			(fill no)
			(layer "F.CrtYd")
		)
		(fp_poly
			(pts
				(xy 1.397 4.5466) (xy 1.397 3.2639) (xy -23.6728 3.2639) (xy -23.6728 -3.5052) (xy 23.6728 -3.5052)
				(xy 23.6728 -0.00635) (xy 22.8727 -0.00635) (xy 22.8727 -2.7559) (xy -22.8727 -2.7559) (xy -22.8727 2.7559)
				(xy 1.905 2.7559) (xy 1.905 3.5179) (xy 8.255 3.5179) (xy 8.255 2.7559) (xy 22.8727 2.7559) (xy 22.8727 0.00635)
				(xy 23.6728 0.00635) (xy 23.6728 3.2639) (xy 8.763 3.2639) (xy 8.763 4.5466)
			)
			(stroke
				(width 0)
				(type default)
			)
			(fill no)
			(layer "F.CrtYd")
		)
		(fp_poly
			(pts
				(xy 1.397 4.5466) (xy 1.397 3.2639) (xy -23.6728 3.2639) (xy -23.6728 -3.5052) (xy 23.6728 -3.5052)
				(xy 23.6728 3.2639) (xy 8.763 3.2639) (xy 8.763 4.5466)
			)
			(stroke
				(width 0)
				(type default)
			)
			(fill no)
			(layer "F.Fab")
		)
		(pad "" np_thru_hole circle
			(at -18.874994 0 270)
			(size 0.254 0.254)
			(drill 1.3462)
			(layers "*.Cu" "*.Mask")
			(clearance 0.9017)
			(thermal_gap 0.9017)
		)
		(pad "" np_thru_hole circle
			(at 18.874994 0 270)
			(size 0.254 0.254)
			(drill 0.9398)
			(layers "*.Cu" "*.Mask")
			(clearance 0.6985)
			(thermal_gap 0.6985)
		)
		(pad "G1" smd rect
			(at 21.874988 0 270)
			(size 2.5908 2.5908)
			(layers "F.Cu" "F.Mask" "F.Paste")
			(net "GND")
		)
		(pad "G2" smd rect
			(at -21.874988 0 270)
			(size 2.5908 2.5908)
			(layers "F.Cu" "F.Mask" "F.Paste")
			(net "GND")
		)
		(pad "P1" smd rect
			(at 1.905 -1.82499 270)
			(size 0.6096 2.3622)
			(layers "F.Cu" "F.Mask" "F.Paste")
			(net "Net_1649")
		)
		(pad "P2" smd rect
			(at 0.635 -1.82499 270)
			(size 0.6096 2.3622)
			(layers "F.Cu" "F.Mask" "F.Paste")
			(net "Net_1650")
		)
		(pad "P3" smd rect
			(at -0.635 -1.82499 270)
			(size 0.6096 2.3622)
			(layers "F.Cu" "F.Mask" "F.Paste")
			(net "Net_1651")
		)
		(pad "P4" smd rect
			(at -1.905 -1.82499 270)
			(size 0.6096 2.3622)
			(layers "F.Cu" "F.Mask" "F.Paste")
			(net "GND")
		)
		(pad "P5" smd rect
			(at -3.175 -1.82499 270)
			(size 0.6096 2.3622)
			(layers "F.Cu" "F.Mask" "F.Paste")
			(net "HDD_PRSNT_29")
		)
		(pad "P6" smd rect
			(at -4.445 -1.82499 270)
			(size 0.6096 2.3622)
			(layers "F.Cu" "F.Mask" "F.Paste")
			(net "GND")
		)
		(pad "P7" smd rect
			(at -5.715 -1.82499 270)
			(size 0.6096 2.3622)
			(layers "F.Cu" "F.Mask" "F.Paste")
			(net "5V_PRE_29")
		)
		(pad "P8" smd rect
			(at -6.985 -1.82499 270)
			(size 0.6096 2.3622)
			(layers "F.Cu" "F.Mask" "F.Paste")
			(net "P5V_HDD29")
		)
		(pad "P9" smd rect
			(at -8.255 -1.82499 270)
			(size 0.6096 2.3622)
			(layers "F.Cu" "F.Mask" "F.Paste")
			(net "P5V_HDD29")
		)
		(pad "P10" smd rect
			(at -9.525 -1.82499 270)
			(size 0.6096 2.3622)
			(layers "F.Cu" "F.Mask" "F.Paste")
			(net "GND")
		)
		(pad "P11" smd rect
			(at -10.795 -1.82499 270)
			(size 0.6096 2.3622)
			(layers "F.Cu" "F.Mask" "F.Paste")
			(net "ACT_HDD_29")
		)
		(pad "P12" smd rect
			(at -12.065 -1.82499 270)
			(size 0.6096 2.3622)
			(layers "F.Cu" "F.Mask" "F.Paste")
			(net "GND")
		)
		(pad "P13" smd rect
			(at -13.335 -1.82499 270)
			(size 0.6096 2.3622)
			(layers "F.Cu" "F.Mask" "F.Paste")
			(net "12V_PRE_29")
		)
		(pad "P14" smd rect
			(at -14.605 -1.82499 270)
			(size 0.6096 2.3622)
			(layers "F.Cu" "F.Mask" "F.Paste")
			(net "P12V_HDD29")
		)
		(pad "P15" smd rect
			(at -15.875 -1.82499 270)
			(size 0.6096 2.3622)
			(layers "F.Cu" "F.Mask" "F.Paste")
			(net "P12V_HDD29")
		)
		(pad "S1" smd rect
			(at 15.875 -1.82499 270)
			(size 0.6096 2.3622)
			(layers "F.Cu" "F.Mask" "F.Paste")
			(net "GND")
		)
		(pad "S2" smd rect
			(at 14.605 -1.82499 270)
			(size 0.6096 2.3622)
			(layers "F.Cu" "F.Mask" "F.Paste")
			(net "SAS_HDD_RX_P29")
		)
		(pad "S3" smd rect
			(at 13.335 -1.82499 270)
			(size 0.6096 2.3622)
			(layers "F.Cu" "F.Mask" "F.Paste")
			(net "SAS_HDD_RX_N29")
		)
		(pad "S4" smd rect
			(at 12.065 -1.82499 270)
			(size 0.6096 2.3622)
			(layers "F.Cu" "F.Mask" "F.Paste")
			(net "GND")
		)
		(pad "S5" smd rect
			(at 10.795 -1.82499 270)
			(size 0.6096 2.3622)
			(layers "F.Cu" "F.Mask" "F.Paste")
			(net "PHY_DRV_B_TO_SCC_B_29_DN")
		)
		(pad "S6" smd rect
			(at 9.525 -1.82499 270)
			(size 0.6096 2.3622)
			(layers "F.Cu" "F.Mask" "F.Paste")
			(net "PHY_DRV_B_TO_SCC_B_29_DP")
		)
		(pad "S7" smd rect
			(at 8.255 -1.82499 270)
			(size 0.6096 2.3622)
			(layers "F.Cu" "F.Mask" "F.Paste")
			(net "GND")
		)
		(pad "S8" smd rect
			(at 7.480046 2.845054 270)
			(size 0.508 2.3622)
			(layers "F.Cu" "F.Mask" "F.Paste")
			(net "GND")
		)
		(pad "S9" smd rect
			(at 6.679946 2.845054 270)
			(size 0.508 2.3622)
			(layers "F.Cu" "F.Mask" "F.Paste")
			(net "Net_454")
		)
		(pad "S10" smd rect
			(at 5.8801 2.845054 270)
			(size 0.508 2.3622)
			(layers "F.Cu" "F.Mask" "F.Paste")
			(net "Net_346")
		)
		(pad "S11" smd rect
			(at 5.08 2.845054 270)
			(size 0.508 2.3622)
			(layers "F.Cu" "F.Mask" "F.Paste")
			(net "GND")
		)
		(pad "S12" smd rect
			(at 4.2799 2.845054 270)
			(size 0.508 2.3622)
			(layers "F.Cu" "F.Mask" "F.Paste")
			(net "Net_382")
		)
		(pad "S13" smd rect
			(at 3.480054 2.845054 270)
			(size 0.508 2.3622)
			(layers "F.Cu" "F.Mask" "F.Paste")
			(net "Net_418")
		)
		(pad "S14" smd rect
			(at 2.679954 2.845054 270)
			(size 0.508 2.3622)
			(layers "F.Cu" "F.Mask" "F.Paste")
			(net "GND")
		)
		(zone
			(layer "F.Cu")
			(hatch none 0.5)
			(connect_pads
				(clearance 0)
			)
			(min_thickness 0.25)
			(keepout
				(tracks allowed)
				(vias not_allowed)
				(pads allowed)
				(copperpour not_allowed)
				(footprints allowed)
			)
			(placement
				(enabled no)
				(sheetname "")
			)
			(fill
				(thermal_gap 0.5)
				(thermal_bridge_width 0.5)
				(island_removal_mode 0)
			)
			(polygon
				(pts
					(xy 189.607698 -45.648626) (xy 182.533798 -45.648626) (xy 182.533798 -52.582826) (xy 183.638698 -52.582826)
					(xy 183.638698 -48.468026) (xy 188.261498 -48.468026) (xy 188.261498 -52.582826) (xy 189.607698 -52.582826)
				)
			)
		)
		(zone
			(layer "F.Cu")
			(hatch none 0.5)
			(connect_pads
				(clearance 0)
			)
			(min_thickness 0.25)
			(keepout
				(tracks not_allowed)
				(vias allowed)
				(pads allowed)
				(copperpour not_allowed)
				(footprints allowed)
			)
			(placement
				(enabled no)
				(sheetname "")
			)
			(fill
				(thermal_gap 0.5)
				(thermal_bridge_width 0.5)
				(island_removal_mode 0)
			)
			(polygon
				(pts
					(xy 189.607698 -45.648626) (xy 182.533798 -45.648626) (xy 182.533798 -52.582826) (xy 183.638698 -52.582826)
					(xy 183.638698 -48.468026) (xy 188.261498 -48.468026) (xy 188.261498 -52.582826) (xy 189.607698 -52.582826)
				)
			)
		)
		(zone
			(layer "F.Cu")
			(hatch none 0.5)
			(connect_pads
				(clearance 0)
			)
			(min_thickness 0.25)
			(keepout
				(tracks not_allowed)
				(vias allowed)
				(pads allowed)
				(copperpour not_allowed)
				(footprints allowed)
			)
			(placement
				(enabled no)
				(sheetname "")
			)
			(fill
				(thermal_gap 0.5)
				(thermal_bridge_width 0.5)
				(island_removal_mode 0)
			)
			(polygon
				(pts
					(xy 189.607698 -12.171426) (xy 182.533798 -12.171426) (xy 182.533798 -5.237226) (xy 183.638698 -5.237226)
					(xy 183.638698 -9.352026) (xy 188.261498 -9.352026) (xy 188.261498 -5.237226) (xy 189.607698 -5.237226)
				)
			)
		)
		(zone
			(layer "F.Cu")
			(hatch none 0.5)
			(connect_pads
				(clearance 0)
			)
			(min_thickness 0.25)
			(keepout
				(tracks allowed)
				(vias not_allowed)
				(pads allowed)
				(copperpour not_allowed)
				(footprints allowed)
			)
			(placement
				(enabled no)
				(sheetname "")
			)
			(fill
				(thermal_gap 0.5)
				(thermal_bridge_width 0.5)
				(island_removal_mode 0)
			)
			(polygon
				(pts
					(xy 189.607698 -12.171426) (xy 182.533798 -12.171426) (xy 182.533798 -5.237226) (xy 183.638698 -5.237226)
					(xy 183.638698 -9.352026) (xy 188.261498 -9.352026) (xy 188.261498 -5.237226) (xy 189.607698 -5.237226)
				)
			)
		)
		(zone
			(layers "F.Cu" "B.Cu" "In1.Cu" "In2.Cu" "In3.Cu" "In4.Cu" "In5.Cu" "In6.Cu")
			(hatch none 0.5)
			(connect_pads
				(clearance 0)
			)
			(min_thickness 0.25)
			(keepout
				(tracks not_allowed)
				(vias allowed)
				(pads allowed)
				(copperpour not_allowed)
				(footprints allowed)
			)
			(placement
				(enabled no)
				(sheetname "")
			)
			(fill
				(thermal_gap 0.5)
				(thermal_bridge_width 0.5)
				(island_removal_mode 0)
			)
			(polygon
				(pts
					(arc
						(start 186.724798 -10.035032)
						(mid 185.175398 -10.035032)
						(end 186.724798 -10.035032)
					)
				)
			)
		)
		(zone
			(layers "F.Cu" "B.Cu" "In1.Cu" "In2.Cu" "In3.Cu" "In4.Cu" "In5.Cu" "In6.Cu")
			(hatch none 0.5)
			(connect_pads
				(clearance 0)
			)
			(min_thickness 0.25)
			(keepout
				(tracks not_allowed)
				(vias allowed)
				(pads allowed)
				(copperpour not_allowed)
				(footprints allowed)
			)
			(placement
				(enabled no)
				(sheetname "")
			)
			(fill
				(thermal_gap 0.5)
				(thermal_bridge_width 0.5)
				(island_removal_mode 0)
			)
			(polygon
				(pts
					(arc
						(start 186.927998 -47.78502)
						(mid 184.972198 -47.78502)
						(end 186.927998 -47.78502)
					)
				)
			)
		)
	)
)
